# Honey Badger FCB BOM.xlsx — Honey Badger FCB BOM (bom)
| Level | Parent Number | Part Number | Description | Green Factor | Life Cycle State | Manufacturer | Manufacturer Part Number | Source | BOM Usage | M/P Code | S/D | Qty | UoM | Location |
| 1 | 91.64W10.A31G | 55.64W02.A21G | KNOX FCB(DIP) | N/A; | Released |  |  |  | M | Manufacture |  | 1 | PCS |  |
| 2 | 55.64W02.A21G | 06.1BETB.14Z | LED RED/BLUE LTL1BETBEK5H149-WN | R2_SA; | Released | LITEON | LTL1BETBEK5H149-WN | Single |  | Purchase | DIP | 6 | PCS | LED1 LED2 LED3 LED4 LED5 LED6 |
| 2 | 55.64W02.A21G | 20.81943.024 | CONN CTR 4P+20S ST 51952-220LF ,PA66 | R2_SA; | Released | FCI | 51952-220LF | Multiple |  | Purchase | DIP | 2 | PCS | CN10 CN9 |
| 2 | 55.64W02.A21G | 21.61427.105 | HEAD ML 1R5P RT A2541WR0-1TX5 ,NYLON6T | R2_SA; | Released | JWT | A2541WR0-1TX5PA-6T | Single |  | Purchase | DIP | 6 | PCS | CN1 CN2 CN3 CN4 CN5 CN6 |
| 2 | 55.64W02.A21G | 21.61942.103 | HAED ML 3P 21S-H91-03GB31 W/JUMPER G/F | R2_SA;HF_SA; | Released | PINREX | 21S-H91-03GB31 | Single |  | Purchase | DIP | 1 | PCS | JP1 |
| 2 | 55.64W02.A21G | 21.63033.103 | HEAD ML 1R3P ST 210-91-03GB01 ,PA9T | R2_SA; | Released | PINREX | 210-91-03GB01 | Multiple |  | Purchase | DIP | 1 | PCS | CN8 |
| 2 | 55.64W02.A21G | 40.58D03.001 | LBL POLYIMIDE31.8*6.35 BARCODE | R2_SA;HF_SA;G_SA; | Released | LABELJET | 40.58D03.001 | Single |  | Purchase | DIP | 2 | PCS |  |
| 2 | 55.64W02.A21G | 40.64W19.001 | LBL YELLOW KNOX 25.5X12.8MM FOR KNOX | R2_SA; | Released | TBD |  | Single |  | Purchase | DIP | 1 | PCS |  |
| 2 | 55.64W02.A21G | 42.64W15.001 | HLDR FAN CONN 1 HU230 | R2_SA; | Released | TBD |  | Single |  | Purchase | DIP | 6 | PCS |  |
| 2 | 55.64W02.A21G | 55.64W02.MA5G | KNOX FAN CONTROLLER BOARD(SMT) | N/A; | Released |  |  |  | M | Manufacture | DIP | 1 | PCS |  |
| 3 | 55.64W02.MA5G | 084.00925.003N | FET MOS PH0925CL NC LFPAK 4P | R2_SA; | Released | NXP | PH0925CL | Single |  | Purchase | SMT | 8 | PCS | PQ1 PQ11 PQ12 PQ13 PQ2 PQ3 PQ7 PQ8 |
| 3 | 55.64W02.MA5G | 34.64W05.001 | BOSS NUT H1.2 M4 | R2_SA; | Released | TBD |  | Single |  | Purchase | SMT | 5 | PCS | H10 H11 H12 H13 H9 |
| 3 | 55.64W02.MA5G | 48.64W04.01M | PCB 12433-1M KNOX_FAN CONTROL BD 4L GCE | R2_SA; | Released | TBD |  | Multiple |  | Purchase | SMT | 1 | PCS |  |
| 3 | 55.64W02.MA5G | 63.00000.00L | CHIP RES 0 J 1/10W 0603 | R2_SA;HF_SA;G_SA; | Released | TA-I ; RALEC ; YAGEO ; WALSIN | RM06JTN0 ; RTT03000JTP ; RC0603JR-070RL ; WR06X000PTL | Multiple |  | Purchase | SMT | 1 | PCS | PR54 |
| 3 | 55.64W02.MA5G | 63.10134.1DL | CHIP RES 100 J 1/16W 0402 | R2_SA;HF_SA;G_SA; | Released | TA-I;RALEC;CYNTEC;YAGEO;WALSIN | RM04JTN101 ; RTT02101JTH ; RR0510S-101-JN ; RC0402JR-07100RL;WR04X101JTL | Multiple |  | Purchase | SMT | 2 | PCS | R360 R361 |
| 3 | 55.64W02.MA5G | 63.10333.15L | CHIP RES 10K J 1/10W 0603 | R2_SA;HF_SA;G_SA; | Released | RALEC;TA-I;YAGEO;WALSIN | RTT03103JTP;RM06JTN103;RC0603JR-0710KL;WR06X103JTL | Multiple |  | Purchase | SMT | 1 | PCS | PR53 |
| 3 | 55.64W02.MA5G | 63.10334.1DL | CHIP RES 10K J 1/16W 0402 | R2_SA;HF_SA;G_SA; | Released | CYNTEC;RALEC;TA-I;WALSIN;YAGEO | RR0510S-103-JN;RTT02103JTH;RM04JTN103;WR04X103JTL;RC0402JR-0710KL | Multiple |  | Purchase | SMT | 1 | PCS | R261 |
| 3 | 55.64W02.MA5G | 63.10434.1DL | CHIP RES 100K J 1/16W 0402 | R2_SA;HF_SA;G_SA; | Released | TA-I;RALEC;CYNTEC;YAGEO;WALSIN | RM04JTN104 ; RTT02104JTH ; RR0510S-104-JN ; RC0402JR-07100KL;WR04X104JTL | Multiple |  | Purchase | SMT | 1 | PCS | R11 |
| 3 | 55.64W02.MA5G | 63.10534.1DL | CHIP RES 1M J 1/16W 0402 | R2_SA;HF_SA;G_SA; | Released | TA-I;RALEC;CYNTEC;YAGEO;WALSIN | RM04JTN105 ; RTT02105JTH ; RR0510S-105-JN ; RC0402JR-071ML;WR04X105JTL | Multiple |  | Purchase | SMT | 1 | PCS | R10 |
| 3 | 55.64W02.MA5G | 63.10634.1DL | CHIP RES 10M J 1/16W 0402 | R2_SA;HF_SA;G_SA; | Released | TA-I;RALEC;CYNTEC;YAGEO;WALSIN | RM04JTN106 ; RTT02106JTH ; RR0510S-106-JN ; RC0402JR-0710ML;WR04X106JTL | Multiple |  | Purchase | SMT | 1 | PCS | R365 |
| 3 | 55.64W02.MA5G | 63.15231.16L | CHIP RES 1.5K J 1/8W 0805(ROHS | R2_SA;HF_SA;G_SA; | Released | TAI;YAGEO;RALEC | RM10JTN152;RC0805JR-071K5L;RTT05152JTP | Multiple |  | Purchase | SMT | 1 | PCS | PR43 |
| 3 | 55.64W02.MA5G | 63.18232.11L | CHIP RES 1.8K J 1/4W 1206 | R2_SA;HF_SA;G_SA; | Released | RALEC ; TA-I ; YAGEO | RTT06182JTP ; RM12JTN182 ; RC1206JR-071K8L | Multiple |  | Purchase | SMT | 6 | PCS | R122 R123 R124 R125 R126 R127 |
| 3 | 55.64W02.MA5G | 63.33134.1DL | CHIP RES 330 J 1/16W 0402 | R2_SA;HF_SA;G_SA; | Released | TA-I;RALEC;CYNTEC;YAGEO;WALSIN | RM04JTN331 ; RTT02331JTH ; RR0510S-331-JN ; RC0402JR-07330RL;WR04X331JTL | Multiple |  | Purchase | SMT | 6 | PCS | R129 R148 R149 R155 R156 R157 |
| 3 | 55.64W02.MA5G | 63.47234.1DL | CHIP RES 4.7K J 1/16W 0402 | R2_SA;HF_SA;G_SA; | Released | TA-I;RALEC;CYNTEC;YAGEO;WALSIN | RM04JTN472 ; RTT02472JTH ; RR0510S-472-JN ; RC0402JR-074K7L;WR04X472JTL | Multiple |  | Purchase | SMT | 9 | PCS | PR47 PR49 R39 R43 R44 R48 R54 R55 R56 |
| 3 | 55.64W02.MA5G | 63.47334.1DL | CHIP RES 47K J 1/16W 0402 | R2_SA;HF_SA;G_SA; | Released | TAI;RALEC;CYNTEC;YAGEO;WALSIN | RM04JTN473 ; RTT02473JTH ; RR0510S-473-JN ; RC0402JR-0747KL;WR04X473JTL | Multiple |  | Purchase | SMT | 1 | PCS | R260 |
| 3 | 55.64W02.MA5G | 63.R0031.16L | CHIP RES 0 J 1/8W 0805 | R2_SA;HF_SA;G_SA; | Released | TA-I ; RALEC ; YAGEO ; WALSIN | RM10JTN0 ; RTT05000JTP ; RC0805JR-070RL ; WR08X000PTL | Multiple |  | Purchase | SMT | 1 | PCS | R8 |
| 3 | 55.64W02.MA5G | 63.R0034.1DL | CHIP RES 0 J 1/16W 0402 | R2_SA;HF_SA;G_SA; | Released | TA-I;RALEC;CYNTEC;YAGEO;WALSIN | RM04JTN0;RTT02000JTH;RR0510X-000-XN;RC0402JR-070RL;WR04X000PTL | Multiple |  | Purchase | SMT | 42 | PCS | PR14 PR94 PR95 PR96 PR97 R1 R106 R107 R108 R109 R136 R137 R138 R139 R140 R141 R164 R165 R171 R172 R173 R174 R175 R176 R183 R184 R2 R26 R28 R30 R32 R34 R364 R38 R4 R45 R46 R47 R5 R51 R62 R63 |
| 3 | 55.64W02.MA5G | 64.0U505.L0L | CHIP RES 0.0005 F 1W 0612 | R2_SA; | Released | VISHAY;CYNTEC | WSK0612L5000FEA;RL1632L4-0R5M-FN | Multiple |  | Purchase | SMT | 3 | PCS | PR29 PR30 PR31 |
| 3 | 55.64W02.MA5G | 64.10005.6DL | CHIP RES 100 F 1/16W 0402 | R2_SA;HF_SA;G_SA; | Released | TA-I ; RALEC ; CYNTEC ; YAGEO;WALSIN | RM04FTN1000 ; RTT021000FTH ; RR0510S-1000-FN ; RC0402FR-07100RL;WR04X1000FTL | Multiple |  | Purchase | SMT | 2 | PCS | PR101 PR99 |
| 3 | 55.64W02.MA5G | 64.10015.6DL | CHIP RES 1K F 1/16W 0402 | R2_SA;HF_SA;G_SA; | Released | TA-I;RALEC;CYNTEC;YAGEO;WALSIN | RM04FTN1001 ; RTT021001FTH ; RR0510S-102-FN ; RC0402FR-071KL;WR04X1001FTL | Multiple |  | Purchase | SMT | 6 | PCS | PR106 PR107 PR16 PR38 PR41 PR7 |
| 3 | 55.64W02.MA5G | 64.10025.6DL | CHIP RES 10K F 1/16W 0402 | R2_SA;HF_SA;G_SA; | Released | TA-I;RALEC;CYNTEC;YAGEO;WALSIN | RM04FTN1002 ; RTT021002FTH ; RR0510S-103-FN ; RC0402FR-0710KL;WR04X1002FTL | Multiple |  | Purchase | SMT | 20 | PCS | PR45 PR58 R102 R103 R104 R105 R128 R15 R35 R359 R366 R367 R74 R75 R76 R77 R88 R89 R90 R91 |
| 3 | 55.64W02.MA5G | 64.10035.6DL | CHIP RES 100K F 1/16W 0402 | R2_SA;HF_SA;G_SA; | Released | TA-I;RALEC;CYNTEC;YAGEO;WALSIN | RM04FTN1003 ; RTT021003FTH ; RR0510S-104-FN ; RC0402FR-07100KL;WR04X1003FTL | Multiple |  | Purchase | SMT | 7 | PCS | PR1 PR55 PR6 R17 R18 R19 R21 |
| 3 | 55.64W02.MA5G | 64.10R05.6DL | CHIP RES 10 F 1/16W 0402 | R2_SA;HF_SA;G_SA; | Released | TA-I ; RALEC ; CYNTEC ; YAGEO | RM04FTN10R0 ; RTT0210R0FTH ; RR0510S-100-FN ; RC0402FR-0710RL | Multiple |  | Purchase | SMT | 17 | PCS | PR102 PR103 PR118 PR119 PR18 PR19 PR2 PR20 PR21 PR22 PR23 PR26 PR27 PR28 PR51 R150 R151 |
| 3 | 55.64W02.MA5G | 64.11025.6DL | CHIP RES 11K F 1/16W 0402 | R2_SA;HF_SA;G_SA; | Released | TA-I ; RALEC ; CYNTEC ; YAGEO;WALSIN | RM04FTN1102 ; RTT021102FTH ; RR0510S-1102-FN ; RC0402FR-0711KL;WR04X1102FTL | Multiple |  | Purchase | SMT | 1 | PCS | PR8 |
| 3 | 55.64W02.MA5G | 64.11035.L0L | CHIP RES 110K F 1/16W 0402 | R2_SA;HF_SA;G_SA; | Released | TA-I;RALEC;CYNTEC | RM04FTN1103;RTT021103FTH;RR0510S-1103-FN | Multiple |  | Purchase | SMT | 3 | PCS | R14 R16 R36 |
| 3 | 55.64W02.MA5G | 64.17835.6DL | CHIP RES 178K F 1/16W 0402 | R2_SA;HF_SA;G_SA; | Released | TAI;RALEC;CYNTEC;YAGEO | RM04FTN1783;RTT021783FTH;RR0510S-1783-FN;RC0402FR-07178KL | Multiple |  | Purchase | SMT | 2 | PCS | PR110 PR111 |
| 3 | 55.64W02.MA5G | 64.20015.6DL | CHIP RES 2K F 1/16W 0402 | R2_SA;HF_SA;G_SA; | Released | TA-I;RALEC;CYNTEC;YAGEO;WALSIN | RM04FTN2001 ; RTT022001FTH ; RR0510S-202-FN ; RC0402FR-072KL;WR04X2001FTL | Multiple |  | Purchase | SMT | 6 | PCS | R111 R113 R115 R117 R119 R121 |
| 3 | 55.64W02.MA5G | 64.20025.6DL | CHIP RES 20K F 1/16W 0402 | R2_SA;HF_SA;G_SA; | Released | TA-I;RALEC;CYNTEC;YAGEO;WALSIN | RM04FTN2002 ; RTT022002FTH ; RR0510S-203-FN ; RC0402FR-0720KL;WR04X2002FTL | Multiple |  | Purchase | SMT | 2 | PCS | PR114 PR115 |
| 3 | 55.64W02.MA5G | 64.22125.55L | CHIP RES 22.1K F 1/10W 0603 | R2_SA;HF_SA;G_SA; | Released | TA-I ; RALEC ; YAGEO | RM06FTN2212 ; RTT032212FTP ; RC0603FR-0722K1L | Multiple |  | Purchase | SMT | 1 | PCS | PR56 |
| 3 | 55.64W02.MA5G | 64.27015.6DL | CHIP RES 2.7K F 1/16W 0402 | R2_SA;HF_SA;G_SA; | Released | TAI;RALEC;CYNTEC;YAGEO | RM04FTN2701;RTT022701FTH;RR0510S-2701-FN;RC0402FR-072K7L | Multiple |  | Purchase | SMT | 2 | PCS | PR104 PR105 |
| 3 | 55.64W02.MA5G | 64.27025.55L | CHIP RES 27K F 1/10W 0603 | R2_SA;HF_SA;G_SA; | Released | TA-I ; RALEC ; YAGEO | RM06FTN2702 ; RTT032702FTP ; RC0603FR-0727KL | Multiple |  | Purchase | SMT | 12 | PCS | R100 R101 R70 R71 R72 R73 R84 R85 R86 R87 R98 R99 |
| 3 | 55.64W02.MA5G | 64.33015.55L | CHIP RES 3.3K F 1/10W 0603(ROH | R2_SA;HF_SA;G_SA; | Released | TAI;RALEC;YAGEO | RM06FTN3301;RTT033301FTP;RC0603FR-073K3L | Multiple |  | Purchase | SMT | 1 | PCS | PR117 |
| 3 | 55.64W02.MA5G | 64.40215.6DL | CHIP RES 4.02K F 1/16W 0402 | R2_SA;HF_SA;G_SA; | Released | TA-I;RALEC;CYNTEC;YAGEO;WALSIN | RM04FTN4021;RTT024021FTH;RR0510S-4021-FN;RC0402FR-074K02L;WR04X4021FTL | Multiple |  | Purchase | SMT | 1 | PCS | PR36 |
| 3 | 55.64W02.MA5G | 64.47005.6DL | CHIP RES 470 F 1/16W 0402 | R2_SA;HF_SA;G_SA; | Released | TA-I;RALEC;CYNTEC;YAGEO | RM04FTN4700;RTT024700FTH;RR0510S-471-FN;RC0402FR-07470RL | Multiple |  | Purchase | SMT | 4 | PCS | R114 R116 R118 R120 |
| 3 | 55.64W02.MA5G | 64.47015.6DL | CHIP RES 4.7K F 1/16W 0402 | R2_SA;HF_SA;G_SA; | Released | TA-I;RALEC;CYNTEC;YAGEO;WALSIN | RM04FTN4701;RTT024701FTH;RR0510S-472-FN;RC0402FR-074K7L;WR04X4701FTL | Multiple |  | Purchase | SMT | 25 | PCS | PR15 PR59 R12 R130 R131 R132 R133 R134 R135 R20 R3 R60 R61 R66 R67 R68 R69 R80 R81 R82 R83 R93 R94 R95 R97 |
| 3 | 55.64W02.MA5G | 64.47025.55L | CHIP RES 47K F 1/10W 0603 | R2_SA;HF_SA;G_SA; | Released | TA-I ; RALEC ; YAGEO | RM06FTN4702 ; RTT034702FTP ; RC0603FR-0747KL | Multiple |  | Purchase | SMT | 1 | PCS | PR52 |
| 3 | 55.64W02.MA5G | 64.49915.6DL | CHIP RES 4.99K F 1/16W 0402 | R2_SA;HF_SA;G_SA; | Released | TA-I;RALEC;CYNTEC;YAGEO;WALSIN | RM04FTN4991 ; RTT024991FTH ; RR0510S-4991-FN ; RC0402FR-074K99L ; WR04X4991FTL | Multiple |  | Purchase | SMT | 1 | PCS | PR37 |
| 3 | 55.64W02.MA5G | 64.49925.6DL | CHIP RES 49.9K F 1/16W 0402 | R2_SA;HF_SA;G_SA; | Released | TA-I ; RALEC ; CYNTEC ; YAGEO ; WALSIN | RM04FTN4992 ; RTT024992FTH ; RR0510S-4992-FN ; RC0402FR-0749K9L ; WR04X4992FTL | Multiple |  | Purchase | SMT | 1 | PCS | PR4 |
| 3 | 55.64W02.MA5G | 64.51015.6DL | CHIP RES 5.1K F 1/16W 0402 | R2_SA;HF_SA;G_SA; | Released | TA-I;RALEC;CYNTEC;YAGEO;WALSIN | RM04FTN5101 ; RTT025101FTH ; RR0510S-512-FN ; RC0402FR-075K1L;WR04X5101FTL | Multiple |  | Purchase | SMT | 2 | PCS | PR39 PR48 |
| 3 | 55.64W02.MA5G | 64.51025.6DL | CHIP RES 51K F 1/16W 0402 | R2_SA;HF_SA;G_SA; | Released | TA-I ; RALEC ; CYNTEC ; YAGEO;WALSIN | RM04FTN5102 ; RTT025102FTH ; RR0510S-513-FN ; RC0402FR-0751KL;WR04X5102FTL | Multiple |  | Purchase | SMT | 3 | PCS | PR33 PR34 PR46 |
| 3 | 55.64W02.MA5G | 64.51125.6DL | CHIP RES 51.1K F 1/16W 0402 | R2_SA;HF_SA;G_SA; | Released | TA-I;RALEC;CYNTEC;YAGEO;WALSIN | RM04FTN5112;RTT025112FTH;RR0510S-5112-FN;RC0402FR-0751K1L;WR04X5112FTL | Multiple |  | Purchase | SMT | 1 | PCS | PR3 |
| 3 | 55.64W02.MA5G | 64.54925.6DL | CHIP RES 54.9K F 1/16W 0402 | R2_SA;HF_SA;G_SA; | Released | TA-I ; RALEC ; CYNTEC ; YAGEO | RM04FTN5492 ; RTT025492FTH ; RR0510S-5492-FN ; RC0402FR-0754K9L | Multiple |  | Purchase | SMT | 1 | PCS | PR40 |
| 3 | 55.64W02.MA5G | 64.68115.6DL | CHIP RES 6.81K F 1/16W 0402 | R2_SA;HF_SA;G_SA; | Released | TAI;RALEC;CYNTEC;YAGEO | RM04FTN6811;RTT026811FTH;RR0510S-6811-FN; RC0402FR-076K81L | Multiple |  | Purchase | SMT | 4 | PCS | PR108 PR109 PR112 PR113 |
| 3 | 55.64W02.MA5G | 64.R0025.97L | CHIP RES 0.002 F 2W 2512 | R2_SA;HF_SA;G_SA; | Released | TAI;CYNTEC;WALSIN | RLM25FEER002;RL-3264-9-R002-FN;WW25RR002FTL | Multiple |  | Purchase | SMT | 4 | PCS | PR60 PR61 PR62 PR63 |
| 3 | 55.64W02.MA5G | 68.00217.561 | CHIP BEAD FCM1608CF-121T03 | R2_SA;HF_SA;G_SA; | Released | TAITECH | FCM1608CF-121T03 | Single |  | Purchase | SMT | 2 | PCS | L1 L2 |
| 3 | 55.64W02.MA5G | 68.2201D.10J | CHIP IND 22UH #A921CY-220M=P3 | R2_SA; | Released | TOKO | #A921CY-220M=P3 | Multiple |  | Purchase | SMT | 1 | PCS | PL7 |
| 3 | 55.64W02.MA5G | 71.07904.A0G | IC H/W MONI NCT7904D LQFP 48P | R2_SA; | Released | NUVOTON | NCT7904D | Single |  | Purchase | SMT | 1 | PCS | U1 |
| 3 | 55.64W02.MA5G | 71.09551.A0W | IC LED BLINK PCA9551PW-T TSSOP | R2_SA; | Released | NXP | PCA9551PW-T | Single |  | Purchase | SMT | 1 | PCS | U6 |
| 3 | 55.64W02.MA5G | 72.02464.00Q | IC EPROM 24LC64T-I/STG TSSOP8P | R2_SA; | Released | MICROCHIP | 24LC64T-I/STG | Single |  | Purchase | SMT | 1 | PCS | U5 |
| 3 | 55.64W02.MA5G | 73.01G32.AHH | IC CMOS 74LVC1G32GW SC70-5 | R2_SA;HF_SA;G_SA; | Released | NXP | 74LVC1G32GW | Single |  | Purchase | SMT | 3 | PCS | U10 U11 U3 |
| 3 | 55.64W02.MA5G | 73.07407.BHB | IC CMOS SN74LV07APWR TSSOP 14P | R2_SA; | Released | TI | SN74LV07APWR | Single |  | Purchase | SMT | 1 | PCS | U7 |
| 3 | 55.64W02.MA5G | 73.07474.BAB | IC CMOS 74AHC74PWR TSOOP 14P | R2_SA; | Released | TI | SN74AHC74PWR | Single |  | Purchase | SMT | 1 | PCS | U8 |
| 3 | 55.64W02.MA5G | 74.01276.B7Z | IC SWAP CTRL ADM1276-3ACPZ-RL LFCSP 20P | R2_SA; | Released | ADI | ADM1276-3ACPZ-RL | Single |  | Purchase | SMT | 1 | PCS | PU1 |
| 3 | 55.64W02.MA5G | 74.02490.A79 | IC PWR CTRL TPS2490DGSR MSOP10 | R2_SA; | Released | TI | TPS2490DGSR | Single |  | Purchase | SMT | 2 | PCS | PU6 PU7 |
| 3 | 55.64W02.MA5G | 74.07368.071 | IC PWM COMPARATOR NCT7368S SOP 8P | R2_SA; | Released | NUVOTON | NCT7368S | Single |  | Purchase | SMT | 1 | PCS | U2 |
| 3 | 55.64W02.MA5G | 74.08201.04P | IC DC/DC REGULATOR SY8201ABC SOT23-6 | R2_SA;HF_SA; | Released | SILERGY | SY8201ABC | Single |  | Purchase | SMT | 1 | PCS | U4 |
| 3 | 55.64W02.MA5G | 77.21561.00L | CHIP CAP POS 15U 25V 25TQC15M | R2_SA;HF_SA;G_SA; | Released | SANYO | 25TQC15M | Single |  | Purchase | SMT | 9 | PCS | TC12 TC13 TC14 TC15 TC16 TC17 TC18 TC4 TC8 |
| 3 | 55.64W02.MA5G | 77.26861.05L | CHIP CAP POS 68U 16V M7343 ESR | R2_SA; | Released | SANYO | 16TQC68MY | Multiple |  | Purchase | SMT | 9 | PCS | TC1 TC10 TC11 TC2 TC3 TC5 TC6 TC7 TC9 |
| 3 | 55.64W02.MA5G | 78.10322.2FL | CHIP CAP C 0.01U 25V K0402 X7R | R2_SA;HF_SA;G_SA; | Released | AVX;DARFON;MURATA;PHYCOMP;SAMSUNG;TAIYO;TDK;MURATA;YAGEO | 04023C103KAT2A;C1005X7R103KFT;GRM155R71E103KA01D;223891715636;CL05B103KA5NNNC;TMK105BJ103KV-F;C1005X7R1E103KT000F;WBM155R71E103KA01D;CC0402KRX7R8BB103 | Multiple |  | Purchase | SMT | 3 | PCS | PC5 PC85 PC86 |
| 3 | 55.64W02.MA5G | 78.10324.2BL | CHIP CAP C 0.01U 50V K0603 X7R | R2_SA;HF_SA;G_SA; | Released | AVX;KEMET;MURATA;PHYCOMP;SAMSUNG;TDK;DARFON;PANASONIC;WALSIN | 06035C103KAT2A;C0603C103K5RAC;GRM188R71H103KA01D;223858615636;CL10B103KB8NNNC;C1608X7R1H103KT;C1608X7R103KGT;ECJ1VB1H103K;0603B103K500CT | Multiple |  | Purchase | SMT | 2 | PCS | PC91 PC92 |
| 3 | 55.64W02.MA5G | 78.10421.2FL | CHIP CAP C 0.1U 16V K0402 X7R | R2_SA;HF_SA;G_SA; | Released | DARFON;MURATA;PHYCOMP;SAMSUNG;TAIYO;TDK;WALSIN;YAGEO | C1005X7R104KET;GRM155R71C104KA88D;223878715649;CL05B104KO5NNNC;EMK105BJ104KV-FR ;C1005X7R1C104KT000F;0402B104K160CT;CC0402KRX7R7BB104 | Multiple |  | Purchase | SMT | 6 | PCS | C2 C254 C256 C4 C5 PC41 |
| 3 | 55.64W02.MA5G | 78.10422.5FL | CHIP CAP C 0.1U 25V K0402 X5R | R2_SA;HF_SA;G_SA; | Released | MURATA;YAGEO;TDK;TAIYO;SAMSUNG;WALSIN;DARFON | GRM155R61E104KA87D;CC0402KRX5R8BB104;C1005X5R1E104KT000E;TMK105BJ104KV-F;CL05A104KA5NNNC;0402X104K250CT;C1005X5R104KFT | Multiple |  | Purchase | SMT | 4 | PCS | C51 C58 PC89 PC90 |
| 3 | 55.64W02.MA5G | 78.10424.2BL | CHIP CAP C 0.1U 50V K0603 X7R | R2_SA;HF_SA;G_SA; | Released | MURATA;TDK;AVX;PHYCOMP;SAMSUNG;DARFON;MATSUKI;WALSIN | GRM188R71H104KA93D;C1608X7R1H104KT000N;06035C104KAT2A;223858615649;CL10B104KB8NNNC;C1608X7R104KGT;MAG03X7R1H104K;0603B104K500CT | Multiple |  | Purchase | SMT | 17 | PCS | C10 C11 C14 C16 C20 C23 C24 C25 C31 C33 C39 C41 C47 C49 C52 C54 PC96 |
| 3 | 55.64W02.MA5G | 78.10521.2BL | CHIP CAP C 1U 16V K0603 X7R | R2_SA;HF_SA;G_SA; | Released | KEMET;MURATA;TAIYO;TDK;PHYCOMP;WALSIN;SAMSUNG;DARFON | C0603C105K4RAC;GRM188R71C105KA12D;EMK107B7105KA-T;C1608X7R1C105KT;223878615663;0603B105K160CT;CL10B105KO8NNNC;C1608X7R105KET | Multiple |  | Purchase | SMT | 7 | PCS | C12 C13 C15 C19 C53 C55 C9 |
| 3 | 55.64W02.MA5G | 78.10522.21L | CHIP CAP C 1U 25V K0805 X7R | R2_SA;HF_SA;G_SA; | Released | TAIYO;TDK;MURATA;SAMSUNG;DARFON;WALSIN | TMK212B7105KG-T;C2012X7R1E105KT;GRM21BR71E105KA99L;CL21B105KAFNNNE;C2012X7R105KFP;0805B105K250CT | Multiple |  | Purchase | SMT | 2 | PCS | PC10 PC9 |
| 3 | 55.64W02.MA5G | 78.10522.5BL | CHIP CAP C 1U 25V K0603 X5R | R2_SA;HF_SA;G_SA; | Released | MURATA;TDK;PHYCOMP;TAIYO;MATSUKI;DARFON;TDK;WALSIN;SAMSUNG;YAGEO | GRM188R61E105KA12D;C1608X5R1E105KT000N;223891613663;TMK107BJ105KA-T;MAG03X5R1E105K;C1608X5R105KFT;C1608X5R1E105KT000N;0603X105K250CT;CL10A105KA8NNNC;CC0603KRX5R8BB105 | Multiple |  | Purchase | SMT | 11 | PCS | C257 C258 C26 C32 C34 C40 C42 C48 C50 PC1 PC4 |
| 3 | 55.64W02.MA5G | 78.10621.22L | CHIP CAP C 10U 16V K1206 X7R | R2_SA;HF_SA;G_SA; | Released | MURATA;TDK;AVX;DARFON;SAMSUNG;TAIYO | GRM31CR71C106KA12L;C3216X7R1C106KT;CM316X7R106K16AT;C3216X7R106KEP;CL31B106KOHNNNE;EMK316B7106KL-T | Multiple |  | Purchase | SMT | 1 | PCS | PC1262 |
| 3 | 55.64W02.MA5G | 78.10622.51L | CHIP CAP C 10U 25V K0805 X5R | R2_SA;HF_SA;G_SA; | Released | MATSUKI;SAMSUNG;TAIYO;AVX;MURATA;TDK;YAGEO | MAG05X5R1E106K;CL21A106KAYNNNE;TMK212BJ106KG-TD;CM21X5R106K25AT;GRM21BR61E106KA73L;C2012X5R1E106KT;CC0805KKX5R8BB106 | Multiple |  | Purchase | SMT | 4 | PCS | C1 C3 PC2 PC95 |
| 3 | 55.64W02.MA5G | 78.10622.52L | CHIP CAP C 10U 25V K1206 X5R | R2_SA;HF_SA;G_SA; | Released | TAIYO;MURATA;AVX;TDK;KEMET;MATSUKI;PHYCOMP;DARFON;SAMSUNG | TMK316BJ106KL-T;GRM31CR61E106KA12L;12063D106KAT2A;C3216X5R1E106KT;C1206C106K3PAC;MAG06X5R1E106K;222291113676;C3216X5R106KFP;CL31A106KAHNNNE | Multiple |  | Purchase | SMT | 1 | PCS | C259 |
| 3 | 55.64W02.MA5G | 78.22034.1BL | CHIP CAP 22P50V J0603 NPO(ROHS | R2_SA;HF_SA;G_SA; | Released | PHYCOMP;MURATA;AVX;TDK;SAMSUNG;DARFON;WALSIN | 223886715229;GRM1885C1H220JA01D;06035A220JAT2A;C1608C0G1H220JT;CL10C220JB8NNNC;C1608NPO220JGT;0603N220J500LT | Multiple |  | Purchase | SMT | 1 | PCS | PC42 |
| 3 | 55.64W02.MA5G | 78.22124.2FL | CHIP CAP C 220P 50V K0402 X7R | R2_SA;HF_SA;G_SA; | Released | MURATA;AVX;TAIYO;PHYCOMN;DARFON | GRM155R71H221KA01D;04025C221KAT2A;UMK105BJ221KV-F;223858715614;C1005X7R221KGT | Multiple |  | Purchase | SMT | 4 | PCS | PC87 PC88 PC93 PC94 |
| 3 | 55.64W02.MA5G | 78.22224.2FL | CHIP CAP C 2200P 50V K0402 X7R | R2_SA;HF_SA;G_SA; | Released | MURATA;AVX;TDK;TAIYO;PHYCOMP;DARFON;SAMSUNG;WALSIN;YAGEO | GRM155R71H222KA01D;04025C222KAT2A;C1005X7R1H222KT000F;UMK105BJ222KV-F;223858715627;C1005X7R222KGT;CL05B222KB5NNNC;0402B222K500CT;CC0402KRX7R9BB222 | Multiple |  | Purchase | SMT | 2 | PCS | C7 C8 |
| 3 | 55.64W02.MA5G | 78.22324.2BL | CHIP CAP C .022U 50V K0603 X7R | R2_SA;HF_SA;G_SA; | Released | MURATA;PHYCOMP;SAMSUNG;TDK;DARFON | GRM188R71H223KA01D;223858615641;CL10B223KB8NNNC;C1608X7R1H223KT;C1608X7R223KGT | Multiple |  | Purchase | SMT | 1 | PCS | PC6 |
| 3 | 55.64W02.MA5G | 78.22611.52L | CHIP CAP 22U 16V M1206 X5R | R2_SA;HF_SA;G_SA; | Released | MURATA;TAIYO;AVX;SAMSUNG | GRM31CR61C226ME15L;EMK316BJ226ML-T;CM316X5R226M16AT;CL31A226KOHNNNE | Multiple |  | Purchase | SMT | 1 | PCS | PC43 |
| 3 | 55.64W02.MA5G | 78.47510.5FL | CHIP CAP C 4.7U 6.3V M0402 X5R | R2_SA;HF_SA;G_SA; | Released | SAMSUNG;TAIYO;MURATA;AVX;YAGEO;WALSIN;DARFON;TDK | CL05A475MQ5NRNC;JDK105BJ475MV-F;GRM155R60J475ME87D;CV05X5R475M06AH065;CC0402MRX5R5BB475;0402X475M6R3CT;C1005X5R475MCT;C1005X5R0J475KT | Multiple |  | Purchase | SMT | 1 | PCS | C6 |
| 3 | 55.64W02.MA5G | 78.47520.5BL | CHIP CAP C 4.7U 6.3V K0603 X5R | R2_SA;HF_SA;G_SA; | Released | MURATA;AVX;PHYCOMP;TAIYO;PANASONIC;TDK;MATSUKI;SAMSUNG;DARFON | GRM188R60J475KE19D;06036D475KAT2A;225520613672;JMK107BJ475KAT;ECJ1VB0J475K;C1608X5R0J475KT;MAG03X5R0J475K;CL10A475KQ8NNNC;C1608X5R475KCT | Multiple |  | Purchase | SMT | 1 | PCS | C253 |
| 3 | 55.64W02.MA5G | 78.47524.L2L | CHIP CAP C 4.7UF 50V K1206 X5R T=0.9 | R2_SA;HF_SA;G_SA; | Released | MURATA;SAMSUNG;TAIYO | GRM319R61H475KA12D;CL31A475KB9LNNC;UMK316BJ475KD-T | Multiple |  | Purchase | SMT | 1 | PCS | PC40 |
| 3 | 55.64W02.MA5G | 82.20034.191 | OSC 33M 3.3V 50PPM HXO-56B SMD | R2_SA; | Released | HOSONIC | D56B33.0000MNS | Single |  | Purchase | SMT | 1 | PCS | OSC1 |
| 3 | 55.64W02.MA5G | 83.00015.0AD | DIODE TVS SMCJ15A SMC | R2_SA; | Released | DIODES | SMCJ15A | Single |  | Purchase | SMT | 1 | PCS | PD2 |
| 3 | 55.64W02.MA5G | 83.00016.A1H | DIODE SW BAS16H 100VSOD123F(GP | R2_SA;G_SA; | Released | NXP | BAS16H | Single |  | Purchase | SMT | 12 | PCS | D1 D10 D11 D12 D2 D3 D4 D5 D6 D7 D8 D9 |
| 3 | 55.64W02.MA5G | 83.1S380.01F | DIODE SW 1SS380TE-17 SOD-323 | R2_SA; | Released | ROHM | 1SS380TE-17 | Single |  | Purchase | SMT | 1 | PCS | D19 |
| 3 | 55.64W02.MA5G | 83.3R004.B8D | DIODE S.B MBRS340T3G 40V3A SMC | R2_SA; | Released | ON | MBRS340T3G | Single |  | Purchase | SMT | 3 | PCS | D14 D15 D16 |
| 3 | 55.64W02.MA5G | 83.3R903.03G | DIODE ZEN 3.9V BZG05C3V9 DO214AC | R2_SA; | Released | VISHAY | BZG05C3V9 | Single |  | Purchase | SMT | 1 | PCS | D13 |
| 3 | 55.64W02.MA5G | 83.R0304.B3F | DIODE CH751H-40PT 40V0.03A | R_SA; | Obsoleted | CHENMKO | CH751H-40PT | Single |  | Purchase | SMT | 1 | PCS | D18 |
| 3 | 55.64W02.MA5G | 84.03904.L06 | XTOR PMBS3904 NPN SOT23 (GP) | R2_SA;HF_SA;G_SA; | Released | NXP | PMBS3904 | Multiple |  | Purchase | SMT | 13 | PCS | PQ10 PQ14 PQ5 PQ6 PQ9 Q1 Q2 Q3 Q4 Q5 Q6 Q7 Q8 |
| 3 | 55.64W02.MA5G | 84.03906.R11 | XTOR MMBT3906 PNP SOT-23 | R2_SA;HF_SA;G_SA; | Released | PANJIT | MMBT3906 | Single |  | Purchase | SMT | 1 | PCS | PQ4 |
| 3 | 55.64W02.MA5G | 84.27002.C3F | FET MOS 2N7002DW-7-F NC SOT363 | R2_SA;HF_SA; | Released | DIODES | 2N7002DW-7-F | Single |  | Purchase | SMT | 1 | PCS | Q10 |
| 3 | 55.64W02.MA5G | 84.27002.W31 | FET MOS 2N7002 NC SOT-23 | R2_SA;HF_SA;G_SA; | Released | PANJIT | 2N7002 | Single |  | Purchase | SMT | 1 | PCS | Q49 |
| 2 | 55.64W02.A21G | 86.00Q43.140 | SCRW NUT HEX M3 | R_SA;G_SA; | Released | TBD |  | Single |  | Purchase | DIP | 4 | PCS |  |
| 2 | 55.64W02.A21G | 86.1A524.100 | SCRW MACH PAN M3*10L | R_SA; | Released | TBD |  | Single |  | Purchase | DIP | 4 | PCS |  |
| 2 | 55.64W02.A21G | 86.HA574.5R0 | SCRW PAN T3 L5 | R2_SA; | Released | TBD |  | Single |  | Purchase | DIP | 12 | PCS |  |
| 2 | 55.64W02.A21G | 88.10301.405 | WASH PLASTIC WS-1C | R2_SA; | Released | TBD |  | Single |  | Purchase | DIP | 12 | PCS |  |
| 1 | 91.64W10.A31G | DP.64W10.A03 | PACKING FOR KNOX FAN CONTROLLER BOARD | N/A; | Released |  |  |  | M | Manufacture |  | 1 | PCS |  |
| 2 | DP.64W10.A03 | 38.09008.001 | DESICANT SILICA GEL 30G H25 | R2_SA; | Released | TBD |  | Single |  | Purchase |  | 1 | PCS |  |
| 2 | DP.64W10.A03 | 40.54T01.001 | LBL CAUTION FOR P97AE | R2_SA;G_SA; | Released | CHENGMAY | 40.54T01.001 | Single |  | Purchase |  | 1 | PCS |  |
| 2 | DP.64W10.A03 | 42.5I405.001 | BAG PE ESD 140*550MM | R2_SA; | Released | TBD |  | Single |  | Purchase |  | 1 | PCS |  |
| 2 | DP.64W10.A03 | 42.60X01.001 | BAG ZIP 320*230MM | R2_SA; | Released | HONGWANG;WINGFUNG | 42.60X01.001 | Multiple |  | Purchase |  | 3.1E-2 | PCS |  |
| 2 | DP.64W10.A03 | 44.5P305.011 | CTN AB B/R 490*390*554MM | R2_SA; | Released | TBD |  | Single |  | Purchase |  | 3.1300000000000001E-2 | PCS |  |
| 2 | DP.64W10.A03 | 45.00005.312 | LBL CTN ART 124*40 B/W ALL | R2_SA;G_SA; | Released | CHENGMAY | 45.00005.312 | Single |  | Purchase |  | 3.1E-2 | PCS |  |
| 2 | DP.64W10.A03 | 45.3B201.001 | LBL CTN 101.6X152.4 H100-ASTRO | R2_SA;HF_SA; | Released | ZHENFENG |  | Single |  | Purchase |  | 3.1300000000000001E-2 | PCS |  |
| 2 | DP.64W10.A03 | 46.30S02.001 | CORNER KRAFT PAPER 900*50*50*3 | R2_SA;HF_SA;G_SA; | Released | KHL;SAFEWAY | 46.30S02.001 | Multiple |  | Purchase |  | 3.5000000000000001E-3 | PCS |  |
| 2 | DP.64W10.A03 | 46.58F01.001 | CORNER PAPER1100*50*50*3 ORIGI | R2_SA;G_SA; | Released | COPLASCO;MYS | 46.58F01.001 | Multiple |  | Purchase |  | 3.5000000000000001E-3 | PCS |  |
| 2 | DP.64W10.A03 | 46.60A03.001 | SHEET AB FLUTE 1200*1000 NS110 | R2_SA;G_SA; | Released | GINYOUNG;TRICAN | 46.60A03.001 | Multiple |  | Purchase |  | 1.8E-3 | PCS |  |
| 2 | DP.64W10.A03 | 46.67E01.001 | CORNER PAPER 1520*50*50*5MM | R2_SA; | Released | TBD |  | Single |  | Purchase |  | 7.0000000000000001E-3 | PCS |  |
| 2 | DP.64W10.A03 | 47.54Z11.001 | CSN PAD EPE 475*375*15MM | R2_SA; | Released | TRICAN | Void | Single |  | Purchase |  | 6.25E-2 | PCS |  |
| 2 | DP.64W10.A03 | 47.57S22.001 | PALLET PLYWOOD 1200*1000*114MM | R2_SA; | Released | JIAMAO | Void | Single |  | Purchase |  | 1.8E-3 | PCS |  |
| 2 | DP.64W10.A03 | 47.5I308.001 | P-PAD AB 479*50MM | R2_SA; | Released | TBD |  | Single |  | Purchase |  | 6.25E-2 | PCS |  |
| 2 | DP.64W10.A03 | 47.5I510.001 | P-PAD AB 380*58MM | R2_SA; | Released | TBD |  | Single |  | Purchase |  | 6.25E-2 | PCS |  |
| 2 | DP.64W10.A03 | 47.5P333.001 | PARTITION A 479*506MM | R2_SA; | Released | TBD |  | Single |  | Purchase |  | 0.15629999999999999 | PCS |  |
| 2 | DP.64W10.A03 | 47.64W05.001 | CSN PARTITION A 506*375MM | R2_SA; | Released | TBD |  | Single |  | Purchase |  | 0.28129999999999999 | PCS |  |
